FILE_TYPE = CONNECTIVITY;
{Allegro Design Entry HDL 16.6-p007 (v16-6-112F) 10/10/2012}
"PAGE_NUMBER" = 98;
0"NC";
1"PVDDQ_ABC\g";
2"PVDDQ_DEF\g";
3"GND\g";
4"PVDDQ_ABC\g";
5"GND\g";
6"PVDDQ_ABC\g";
7"GND\g";
8"GND\g";
9"GND\g";
10"GND\g";
11"PVDDQ_DEF\g";
12"PVDDQ_DEF\g";
13"M_A_VREF";
14"M_D_CPU_VREF";
15"M_A_CPU_VREF";
16"M_D_VREF";
17"M_E_CPU_VREF";
18"M_B_CPU_VREF";
19"M_E_VREF";
20"M_B_VREF";
21"M_F_CPU_VREF";
22"M_C_CPU_VREF";
23"M_F_VREF";
24"M_C_VREF";
%"PVDDQ_ABC"
"1","(-1800,4600)","0","mstr_symbols","I1";
;
VOLTAGE"1.2V"
CDS_LIB"mstr_symbols"
BODY_TYPE"PLUMBING"
HDL_POWER"PVDDQ_ABC";
"G\NAC"1;
%"PVDDQ_DEF"
"1","(-1800,2925)","0","mstr_symbols","I10";
;
VOLTAGE"1.2V"
CDS_LIB"mstr_symbols"
BODY_TYPE"PLUMBING"
HDL_POWER"PVDDQ_DEF";
"G\NAC"2;
%"RES"
"2","(-1725,2025)","2","mstr_discrete","I12";
;
CDS_SEC"1"
LOCATION"R6L16"
PART_NUMBER"G21796-026"
VALUE"1.00K"
TOLERANCE"1%"
PACK_TYPE"0402"
MATERIAL"CHIP"
WATTAGE"1/16W"
CDS_LIB"mstr_discrete"
BOM_COST"PROC_SOCKET"
SEC_TYPE"0402"
SEC"1"
CDS_LOCATION"R6L16"
ROOM"PROC";
"A"
$PN"1"16;
"B"
$PN"2"3;
%"GND"
"1","(-2025,1700)","0","mstr_symbols","I13";
;
VOLTAGE"0"
CDS_LIB"mstr_symbols"
SIZE"1B"
BODY_TYPE"PLUMBING"
HDL_POWER"GND";
"A\NAC"3;
%"RES"
"1","(-2025,2350)","0","mstr_discrete","I14";
;
CDS_SEC"1"
LOCATION"R6M2"
PART_NUMBER"G21796-274"
VALUE"2"
TOLERANCE"1.0%"
PACK_TYPE"0402"
MATERIAL"CHIP"
WATTAGE"1/16W"
CDS_LIB"mstr_discrete"
BOM_COST"PROC_SOCKET"
SEC_TYPE"0402"
SEC"1"
CDS_LOCATION"R6M2"
ROOM"PROC";
"B"
$PN"2"16;
"A"
$PN"1"14;
%"CAP_A"
"1","(-2250,2050)","0","dev_discrete","I33";
;
LOCATION"C6M2"
PART_NUMBER"A36096-045"
VALUE"0.01UF"
TOLERANCE"10%"
PACK_TYPE"0402V"
VOLTAGE"25V"
MATERIAL"X7R"
CDS_LOCATION"C6M2"
BOM_COST"SM_CONTROLLER"
CDS_LIB"dev_discrete"
CDS_SEC"1"
SEC_TYPE"0402V"
SEC"1"
ROOM"MEM";
"B"
$PN"2"3;
"A"
$PN"1"14;
%"RES"
"2","(-1800,4350)","2","mstr_discrete","I36";
;
CDS_SEC"1"
LOCATION"R4F4"
PART_NUMBER"G21796-026"
VALUE"1.00K"
TOLERANCE"1%"
PACK_TYPE"0402"
MATERIAL"CHIP"
WATTAGE"1/16W"
SEC_TYPE"0402"
CDS_LIB"mstr_discrete"
BOM_COST"SM_CONTROLLER"
SEC"1"
CDS_LOCATION"R4F4"
ROOM"MEM";
"A"
$PN"1"1;
"B"
$PN"2"13;
%"PVDDQ_ABC"
"1","(250,4600)","0","mstr_symbols","I37";
;
VOLTAGE"1.2V"
CDS_LIB"mstr_symbols"
BODY_TYPE"PLUMBING"
HDL_POWER"PVDDQ_ABC";
"G\NAC"4;
%"RES"
"2","(250,4350)","2","mstr_discrete","I38";
;
CDS_SEC"1"
PART_NUMBER"G21796-026"
VALUE"1.00K"
TOLERANCE"1%"
PACK_TYPE"0402"
MATERIAL"CHIP"
WATTAGE"1/16W"
LOCATION"R4G2"
BOM_COST"SM_CONTROLLER"
CDS_LIB"mstr_discrete"
SEC_TYPE"0402"
SEC"1"
CDS_LOCATION"R4G2"
ROOM"MEM";
"A"
$PN"1"4;
"B"
$PN"2"20;
%"RES"
"2","(-1725,3700)","2","mstr_discrete","I4";
;
CDS_SEC"1"
LOCATION"R4F5"
PART_NUMBER"G21796-026"
VALUE"1.00K"
TOLERANCE"1%"
PACK_TYPE"0402"
MATERIAL"CHIP"
WATTAGE"1/16W"
SEC_TYPE"0402"
BOM_COST"PROC_SOCKET"
CDS_LIB"mstr_discrete"
SEC"1"
CDS_LOCATION"R4F5"
ROOM"PROC";
"A"
$PN"1"13;
"B"
$PN"2"9;
%"RES"
"2","(325,3700)","2","mstr_discrete","I40";
;
CDS_SEC"1"
LOCATION"R4G3"
PART_NUMBER"G21796-026"
VALUE"1.00K"
TOLERANCE"1%"
PACK_TYPE"0402"
MATERIAL"CHIP"
WATTAGE"1/16W"
CDS_LIB"mstr_discrete"
BOM_COST"PROC_SOCKET"
SEC_TYPE"0402"
SEC"1"
CDS_LOCATION"R4G3"
ROOM"PROC";
"A"
$PN"1"20;
"B"
$PN"2"5;
%"GND"
"1","(25,3375)","0","mstr_symbols","I41";
;
VOLTAGE"0"
SIZE"1B"
CDS_LIB"mstr_symbols"
BODY_TYPE"PLUMBING"
HDL_POWER"GND";
"A\NAC"5;
%"RES"
"1","(25,4025)","0","mstr_discrete","I42";
;
CDS_SEC"1"
LOCATION"R4G1"
PART_NUMBER"G21796-274"
VALUE"2"
TOLERANCE"1.0%"
PACK_TYPE"0402"
MATERIAL"CHIP"
WATTAGE"1/16W"
CDS_LIB"mstr_discrete"
BOM_COST"PROC_SOCKET"
SEC_TYPE"0402"
SEC"1"
CDS_LOCATION"R4G1"
ROOM"PROC";
"B"
$PN"2"20;
"A"
$PN"1"18;
%"CAP_A"
"1","(-200,3725)","0","dev_discrete","I43";
;
LOCATION"C4G1"
PART_NUMBER"A36096-045"
VALUE"0.01UF"
TOLERANCE"10%"
PACK_TYPE"0402V"
VOLTAGE"25V"
MATERIAL"X7R"
CDS_LOCATION"C4G1"
BOM_COST"SM_CONTROLLER"
CDS_LIB"dev_discrete"
CDS_SEC"1"
SEC_TYPE"0402V"
SEC"1"
ROOM"MEM";
"B"
$PN"2"5;
"A"
$PN"1"18;
%"PVDDQ_ABC"
"1","(2400,4600)","0","mstr_symbols","I45";
;
VOLTAGE"1.2V"
CDS_LIB"mstr_symbols"
BODY_TYPE"PLUMBING"
HDL_POWER"PVDDQ_ABC";
"G\NAC"6;
%"RES"
"2","(2400,4350)","2","mstr_discrete","I46";
;
CDS_SEC"1"
LOCATION"R4G21"
PART_NUMBER"G21796-026"
VALUE"1.00K"
TOLERANCE"1%"
PACK_TYPE"0402"
MATERIAL"CHIP"
WATTAGE"1/16W"
BOM_COST"SM_CONTROLLER"
CDS_LIB"mstr_discrete"
SEC_TYPE"0402"
SEC"1"
CDS_LOCATION"R4G21"
ROOM"MEM";
"A"
$PN"1"6;
"B"
$PN"2"24;
%"RES"
"2","(2475,3700)","2","mstr_discrete","I48";
;
CDS_SEC"1"
LOCATION"R4G22"
PART_NUMBER"G21796-026"
VALUE"1.00K"
TOLERANCE"1%"
PACK_TYPE"0402"
MATERIAL"CHIP"
WATTAGE"1/16W"
CDS_LIB"mstr_discrete"
BOM_COST"PROC_SOCKET"
SEC_TYPE"0402"
SEC"1"
CDS_LOCATION"R4G22"
ROOM"PROC";
"A"
$PN"1"24;
"B"
$PN"2"7;
%"GND"
"1","(2175,3375)","0","mstr_symbols","I49";
;
VOLTAGE"0"
SIZE"1B"
CDS_LIB"mstr_symbols"
BODY_TYPE"PLUMBING"
HDL_POWER"GND";
"A\NAC"7;
%"RES"
"1","(-2025,4025)","0","mstr_discrete","I5";
;
CDS_SEC"1"
LOCATION"R4F3"
PART_NUMBER"G21796-274"
VALUE"2"
TOLERANCE"1.0%"
PACK_TYPE"0402"
MATERIAL"CHIP"
WATTAGE"1/16W"
SEC_TYPE"0402"
BOM_COST"PROC_SOCKET"
CDS_LIB"mstr_discrete"
SEC"1"
CDS_LOCATION"R4F3"
ROOM"PROC";
"B"
$PN"2"13;
"A"
$PN"1"15;
%"RES"
"1","(2175,4025)","0","mstr_discrete","I50";
;
CDS_SEC"1"
LOCATION"R4G20"
PART_NUMBER"G21796-274"
VALUE"2"
TOLERANCE"1.0%"
PACK_TYPE"0402"
MATERIAL"CHIP"
WATTAGE"1/16W"
CDS_LIB"mstr_discrete"
BOM_COST"PROC_SOCKET"
SEC_TYPE"0402"
SEC"1"
CDS_LOCATION"R4G20"
ROOM"PROC";
"B"
$PN"2"24;
"A"
$PN"1"22;
%"CAP_A"
"1","(1950,3725)","0","dev_discrete","I51";
;
LOCATION"C4G17"
PART_NUMBER"A36096-045"
VALUE"0.01UF"
TOLERANCE"10%"
PACK_TYPE"0402V"
VOLTAGE"25V"
MATERIAL"X7R"
CDS_LOCATION"C4G17"
BOM_COST"SM_CONTROLLER"
CDS_LIB"dev_discrete"
CDS_SEC"1"
SEC_TYPE"0402V"
SEC"1"
ROOM"MEM";
"B"
$PN"2"7;
"A"
$PN"1"22;
%"RES"
"2","(225,2675)","2","mstr_discrete","I54";
;
CDS_SEC"1"
LOCATION"R6L13"
PART_NUMBER"G21796-026"
VALUE"1.00K"
TOLERANCE"1%"
PACK_TYPE"0402"
MATERIAL"CHIP"
WATTAGE"1/16W"
BOM_COST"SM_CONTROLLER"
CDS_LIB"mstr_discrete"
SEC_TYPE"0402"
SEC"1"
CDS_LOCATION"R6L13"
ROOM"MEM";
"A"
$PN"1"11;
"B"
$PN"2"19;
%"RES"
"2","(300,2025)","2","mstr_discrete","I56";
;
CDS_SEC"1"
LOCATION"R6L12"
PART_NUMBER"G21796-026"
VALUE"1.00K"
TOLERANCE"1%"
PACK_TYPE"0402"
MATERIAL"CHIP"
WATTAGE"1/16W"
CDS_LIB"mstr_discrete"
BOM_COST"PROC_SOCKET"
SEC_TYPE"0402"
SEC"1"
CDS_LOCATION"R6L12"
ROOM"PROC";
"A"
$PN"1"19;
"B"
$PN"2"8;
%"GND"
"1","(0,1700)","0","mstr_symbols","I57";
;
VOLTAGE"0"
SIZE"1B"
CDS_LIB"mstr_symbols"
BODY_TYPE"PLUMBING"
HDL_POWER"GND";
"A\NAC"8;
%"RES"
"1","(0,2350)","0","mstr_discrete","I58";
;
CDS_SEC"1"
LOCATION"R6L14"
PART_NUMBER"G21796-274"
VALUE"2"
TOLERANCE"1.0%"
PACK_TYPE"0402"
MATERIAL"CHIP"
WATTAGE"1/16W"
CDS_LIB"mstr_discrete"
BOM_COST"PROC_SOCKET"
SEC_TYPE"0402"
SEC"1"
CDS_LOCATION"R6L14"
ROOM"PROC";
"B"
$PN"2"19;
"A"
$PN"1"17;
%"CAP_A"
"1","(-225,2050)","0","dev_discrete","I59";
;
LOCATION"C6L7"
PART_NUMBER"A36096-045"
VALUE"0.01UF"
TOLERANCE"10%"
PACK_TYPE"0402V"
VOLTAGE"25V"
MATERIAL"X7R"
CDS_LOCATION"C6L7"
BOM_COST"SM_CONTROLLER"
CDS_LIB"dev_discrete"
CDS_SEC"1"
SEC_TYPE"0402V"
SEC"1"
ROOM"MEM";
"B"
$PN"2"8;
"A"
$PN"1"17;
%"GND"
"1","(-2025,3375)","0","mstr_symbols","I6";
;
VOLTAGE"0"
CDS_LIB"mstr_symbols"
SIZE"1B"
BODY_TYPE"PLUMBING"
HDL_POWER"GND";
"A\NAC"9;
%"RES"
"2","(2400,2650)","2","mstr_discrete","I62";
;
CDS_SEC"1"
LOCATION"R6L2"
PART_NUMBER"G21796-026"
VALUE"1.00K"
TOLERANCE"1%"
PACK_TYPE"0402"
MATERIAL"CHIP"
WATTAGE"1/16W"
BOM_COST"SM_CONTROLLER"
CDS_LIB"mstr_discrete"
SEC_TYPE"0402"
SEC"1"
CDS_LOCATION"R6L2"
ROOM"MEM";
"A"
$PN"1"12;
"B"
$PN"2"23;
%"RES"
"2","(2475,2000)","2","mstr_discrete","I64";
;
CDS_SEC"1"
LOCATION"R6L1"
PART_NUMBER"G21796-026"
VALUE"1.00K"
TOLERANCE"1%"
PACK_TYPE"0402"
MATERIAL"CHIP"
WATTAGE"1/16W"
CDS_LIB"mstr_discrete"
BOM_COST"PROC_SOCKET"
SEC_TYPE"0402"
SEC"1"
CDS_LOCATION"R6L1"
ROOM"PROC";
"A"
$PN"1"23;
"B"
$PN"2"10;
%"GND"
"1","(2175,1675)","0","mstr_symbols","I65";
;
VOLTAGE"0"
SIZE"1B"
CDS_LIB"mstr_symbols"
BODY_TYPE"PLUMBING"
HDL_POWER"GND";
"A\NAC"10;
%"RES"
"1","(2175,2325)","0","mstr_discrete","I66";
;
CDS_SEC"1"
LOCATION"R6L3"
PART_NUMBER"G21796-274"
VALUE"2"
TOLERANCE"1.0%"
PACK_TYPE"0402"
MATERIAL"CHIP"
WATTAGE"1/16W"
CDS_LIB"mstr_discrete"
BOM_COST"PROC_SOCKET"
SEC_TYPE"0402"
SEC"1"
CDS_LOCATION"R6L3"
ROOM"PROC";
"B"
$PN"2"23;
"A"
$PN"1"21;
%"CAP_A"
"1","(1950,2025)","0","dev_discrete","I67";
;
LOCATION"C6L2"
PART_NUMBER"A36096-045"
VALUE"0.01UF"
TOLERANCE"10%"
PACK_TYPE"0402V"
VOLTAGE"25V"
MATERIAL"X7R"
CDS_LOCATION"C6L2"
BOM_COST"SM_CONTROLLER"
CDS_LIB"dev_discrete"
CDS_SEC"1"
SEC_TYPE"0402V"
SEC"1"
ROOM"MEM";
"B"
$PN"2"10;
"A"
$PN"1"21;
%"PVDDQ_DEF"
"1","(225,2925)","0","mstr_symbols","I69";
;
VOLTAGE"1.2V"
CDS_LIB"mstr_symbols"
BODY_TYPE"PLUMBING"
HDL_POWER"PVDDQ_DEF";
"G\NAC"11;
%"CAP_A"
"1","(-2250,3725)","0","dev_discrete","I7";
;
LOCATION"C4F9"
PART_NUMBER"A36096-045"
VALUE"0.01UF"
TOLERANCE"10%"
PACK_TYPE"0402V"
VOLTAGE"25V"
MATERIAL"X7R"
CDS_LOCATION"C4F9"
BOM_COST"SM_CONTROLLER"
CDS_LIB"dev_discrete"
CDS_SEC"1"
SEC_TYPE"0402V"
SEC"1"
ROOM"MEM";
"B"
$PN"2"9;
"A"
$PN"1"15;
%"PVDDQ_DEF"
"1","(2400,2900)","0","mstr_symbols","I70";
;
VOLTAGE"1.2V"
CDS_LIB"mstr_symbols"
BODY_TYPE"PLUMBING"
HDL_POWER"PVDDQ_DEF";
"G\NAC"12;
%"RES"
"2","(-1800,2675)","2","mstr_discrete","I9";
;
CDS_SEC"1"
LOCATION"R6M1"
PART_NUMBER"G21796-026"
VALUE"1.00K"
TOLERANCE"1%"
PACK_TYPE"0402"
MATERIAL"CHIP"
WATTAGE"1/16W"
CDS_LIB"mstr_discrete"
BOM_COST"PROC_SOCKET"
SEC_TYPE"0402"
SEC"1"
CDS_LOCATION"R6M1"
ROOM"MEM";
"A"
$PN"1"2;
"B"
$PN"2"16;
END.
